(kicad_pcb
	(version 20260206)
	(generator "pcbnew")
	(generator_version "10.0")
	(general
		(thickness 1.6)
		(legacy_teardrops no)
	)
	(paper "A4")
	(title_block
		(title "12092022_DA0F0TMDCD0_F0T_Management_Board_D_brd_V3_OCP.brd")
		(comment 1 "Grand Teton / footprint 201 of 1440 (U1), pads 1-96 of 96")
	)
	(layers
		(0 "F.Cu" signal "TOP")
		(4 "In1.Cu" signal "GND")
		(6 "In2.Cu" signal "IN1")
		(8 "In3.Cu" signal "GND1")
		(10 "In4.Cu" signal "IN2")
		(12 "In5.Cu" signal "VCC")
		(14 "In6.Cu" signal "VCC1")
		(16 "In7.Cu" signal "IN3")
		(18 "In8.Cu" signal "GND2")
		(20 "In9.Cu" signal "IN4")
		(22 "In10.Cu" signal "GND3")
		(2 "B.Cu" signal "BOTTOM")
		(9 "F.Adhes" user "F.Adhesive")
		(11 "B.Adhes" user "B.Adhesive")
		(13 "F.Paste" user "Package Geometry/Pastemask Top")
		(15 "B.Paste" user "Package Geometry/Pastemask Bottom")
		(5 "F.SilkS" user "Ref Des/Silkscreen Top")
		(7 "B.SilkS" user "Ref Des/Silkscreen Bottom")
		(1 "F.Mask" user "Board Geometry/Soldermask Top")
		(3 "B.Mask" user "Board Geometry/Soldermask Bottom")
		(17 "Dwgs.User" user "User.Drawings")
		(19 "Cmts.User" user "User.Comments")
		(21 "Eco1.User" user "User.Eco1")
		(23 "Eco2.User" user "User.Eco2")
		(25 "Edge.Cuts" user "Board Geometry/Outline")
		(27 "Margin" user)
		(31 "F.CrtYd" user "Package Geometry/Place Bound Top")
		(29 "B.CrtYd" user "Package Geometry/Place Bound Bottom")
		(35 "F.Fab" user "Ref Des/Assembly Top")
		(33 "B.Fab" user "Ref Des/Assembly Bottom")
	)
	(footprint ""
		(layer "F.Cu")
		(at 76.252324 -47.907448)
		(property "Reference" "U1"
			(at -4.664456 -10.397744 0)
			(unlocked yes)
			(layer "F.SilkS")
			(effects
				(font
					(size 0.7874 0.5842)
					(thickness 0.1524)
				)
				(justify left)
			)
		)
		(property "Value" ""
			(at 0 0 0)
			(layer "F.Fab")
			(effects
				(font
					(size 1.27 1.27)
				)
			)
		)
		(duplicate_pad_numbers_are_jumpers no)
		(pad "A1" smd circle
			(at -3.199892 -5.999988)
			(size 0.3683 0.3683)
			(layers "F.Cu" "F.Mask" "F.Paste")
			(net "P1V2_AUX")
		)
		(pad "A2" smd circle
			(at -2.400046 -5.999988)
			(size 0.3683 0.3683)
			(layers "F.Cu" "F.Mask" "F.Paste")
			(net "GND")
		)
		(pad "A3" smd circle
			(at -1.599946 -5.999988)
			(size 0.3683 0.3683)
			(layers "F.Cu" "F.Mask" "F.Paste")
			(net "M_BMC_DDR4_DQ<8>")
		)
		(pad "A7" smd circle
			(at 1.599946 -5.999988)
			(size 0.3683 0.3683)
			(layers "F.Cu" "F.Mask" "F.Paste")
			(net "M_BMC_DDR4_DQS1_N")
		)
		(pad "A8" smd circle
			(at 2.400046 -5.999988)
			(size 0.3683 0.3683)
			(layers "F.Cu" "F.Mask" "F.Paste")
			(net "GND")
		)
		(pad "A9" smd circle
			(at 3.199892 -5.999988)
			(size 0.3683 0.3683)
			(layers "F.Cu" "F.Mask" "F.Paste")
			(net "P1V2_AUX")
		)
		(pad "B1" smd circle
			(at -3.199892 -5.199888)
			(size 0.3683 0.3683)
			(layers "F.Cu" "F.Mask" "F.Paste")
			(net "P2V5_AUX")
		)
		(pad "B2" smd circle
			(at -2.400046 -5.199888)
			(size 0.3683 0.3683)
			(layers "F.Cu" "F.Mask" "F.Paste")
			(net "GND")
		)
		(pad "B3" smd circle
			(at -1.599946 -5.199888)
			(size 0.3683 0.3683)
			(layers "F.Cu" "F.Mask" "F.Paste")
			(net "P1V2_AUX")
		)
		(pad "B7" smd circle
			(at 1.599946 -5.199888)
			(size 0.3683 0.3683)
			(layers "F.Cu" "F.Mask" "F.Paste")
			(net "M_BMC_DDR4_DQS1_P")
		)
		(pad "B8" smd circle
			(at 2.400046 -5.199888)
			(size 0.3683 0.3683)
			(layers "F.Cu" "F.Mask" "F.Paste")
			(net "M_BMC_DDR4_DQ<9>")
		)
		(pad "B9" smd circle
			(at 3.199892 -5.199888)
			(size 0.3683 0.3683)
			(layers "F.Cu" "F.Mask" "F.Paste")
			(net "P1V2_AUX")
		)
		(pad "C1" smd circle
			(at -3.199892 -4.400042)
			(size 0.3683 0.3683)
			(layers "F.Cu" "F.Mask" "F.Paste")
			(net "P1V2_AUX")
		)
		(pad "C2" smd circle
			(at -2.400046 -4.400042)
			(size 0.3683 0.3683)
			(layers "F.Cu" "F.Mask" "F.Paste")
			(net "M_BMC_DDR4_DQ<12>")
		)
		(pad "C3" smd circle
			(at -1.599946 -4.400042)
			(size 0.3683 0.3683)
			(layers "F.Cu" "F.Mask" "F.Paste")
			(net "M_BMC_DDR4_DQ<10>")
		)
		(pad "C7" smd circle
			(at 1.599946 -4.400042)
			(size 0.3683 0.3683)
			(layers "F.Cu" "F.Mask" "F.Paste")
			(net "M_BMC_DDR4_DQ<11>")
		)
		(pad "C8" smd circle
			(at 2.400046 -4.400042)
			(size 0.3683 0.3683)
			(layers "F.Cu" "F.Mask" "F.Paste")
			(net "M_BMC_DDR4_DQ<13>")
		)
		(pad "C9" smd circle
			(at 3.199892 -4.400042)
			(size 0.3683 0.3683)
			(layers "F.Cu" "F.Mask" "F.Paste")
			(net "GND")
		)
		(pad "D1" smd circle
			(at -3.199892 -3.599942)
			(size 0.3683 0.3683)
			(layers "F.Cu" "F.Mask" "F.Paste")
			(net "P1V2_AUX")
		)
		(pad "D2" smd circle
			(at -2.400046 -3.599942)
			(size 0.3683 0.3683)
			(layers "F.Cu" "F.Mask" "F.Paste")
			(net "GND")
		)
		(pad "D3" smd circle
			(at -1.599946 -3.599942)
			(size 0.3683 0.3683)
			(layers "F.Cu" "F.Mask" "F.Paste")
			(net "M_BMC_DDR4_DQ<14>")
		)
		(pad "D7" smd circle
			(at 1.599946 -3.599942)
			(size 0.3683 0.3683)
			(layers "F.Cu" "F.Mask" "F.Paste")
			(net "M_BMC_DDR4_DQ<15>")
		)
		(pad "D8" smd circle
			(at 2.400046 -3.599942)
			(size 0.3683 0.3683)
			(layers "F.Cu" "F.Mask" "F.Paste")
			(net "GND")
		)
		(pad "D9" smd circle
			(at 3.199892 -3.599942)
			(size 0.3683 0.3683)
			(layers "F.Cu" "F.Mask" "F.Paste")
			(net "P1V2_AUX")
		)
		(pad "E1" smd circle
			(at -3.199892 -2.800096)
			(size 0.3683 0.3683)
			(layers "F.Cu" "F.Mask" "F.Paste")
			(net "GND")
		)
		(pad "E2" smd circle
			(at -2.400046 -2.800096)
			(size 0.3683 0.3683)
			(layers "F.Cu" "F.Mask" "F.Paste")
			(net "M_BMC_DDR4_MDM1")
		)
		(pad "E3" smd circle
			(at -1.599946 -2.800096)
			(size 0.3683 0.3683)
			(layers "F.Cu" "F.Mask" "F.Paste")
			(net "GND")
		)
		(pad "E7" smd circle
			(at 1.599946 -2.800096)
			(size 0.3683 0.3683)
			(layers "F.Cu" "F.Mask" "F.Paste")
			(net "M_BMC_DDR4_MDM0")
		)
		(pad "E8" smd circle
			(at 2.400046 -2.800096)
			(size 0.3683 0.3683)
			(layers "F.Cu" "F.Mask" "F.Paste")
			(net "GND")
		)
		(pad "E9" smd circle
			(at 3.199892 -2.800096)
			(size 0.3683 0.3683)
			(layers "F.Cu" "F.Mask" "F.Paste")
			(net "M_BMC_DDR4_ZQU")
		)
		(pad "F1" smd circle
			(at -3.199892 -1.999996)
			(size 0.3683 0.3683)
			(layers "F.Cu" "F.Mask" "F.Paste")
			(net "GND")
		)
		(pad "F2" smd circle
			(at -2.400046 -1.999996)
			(size 0.3683 0.3683)
			(layers "F.Cu" "F.Mask" "F.Paste")
			(net "P1V2_AUX")
		)
		(pad "F3" smd circle
			(at -1.599946 -1.999996)
			(size 0.3683 0.3683)
			(layers "F.Cu" "F.Mask" "F.Paste")
			(net "M_BMC_DDR4_DQS0_N")
		)
		(pad "F7" smd circle
			(at 1.599946 -1.999996)
			(size 0.3683 0.3683)
			(layers "F.Cu" "F.Mask" "F.Paste")
			(net "M_BMC_DDR4_DQ<1>")
		)
		(pad "F8" smd circle
			(at 2.400046 -1.999996)
			(size 0.3683 0.3683)
			(layers "F.Cu" "F.Mask" "F.Paste")
			(net "P1V2_AUX")
		)
		(pad "F9" smd circle
			(at 3.199892 -1.999996)
			(size 0.3683 0.3683)
			(layers "F.Cu" "F.Mask" "F.Paste")
			(net "PD_M_BMC_DDR4_ZQ")
		)
		(pad "G1" smd circle
			(at -3.199892 -1.199896)
			(size 0.3683 0.3683)
			(layers "F.Cu" "F.Mask" "F.Paste")
			(net "P1V2_AUX")
		)
		(pad "G2" smd circle
			(at -2.400046 -1.199896)
			(size 0.3683 0.3683)
			(layers "F.Cu" "F.Mask" "F.Paste")
			(net "M_BMC_DDR4_DQ<0>")
		)
		(pad "G3" smd circle
			(at -1.599946 -1.199896)
			(size 0.3683 0.3683)
			(layers "F.Cu" "F.Mask" "F.Paste")
			(net "M_BMC_DDR4_DQS0_P")
		)
		(pad "G7" smd circle
			(at 1.599946 -1.199896)
			(size 0.3683 0.3683)
			(layers "F.Cu" "F.Mask" "F.Paste")
			(net "P1V2_AUX")
		)
		(pad "G8" smd circle
			(at 2.400046 -1.199896)
			(size 0.3683 0.3683)
			(layers "F.Cu" "F.Mask" "F.Paste")
			(net "GND")
		)
		(pad "G9" smd circle
			(at 3.199892 -1.199896)
			(size 0.3683 0.3683)
			(layers "F.Cu" "F.Mask" "F.Paste")
			(net "P1V2_AUX")
		)
		(pad "H1" smd circle
			(at -3.199892 -0.40005)
			(size 0.3683 0.3683)
			(layers "F.Cu" "F.Mask" "F.Paste")
			(net "GND")
		)
		(pad "H2" smd circle
			(at -2.400046 -0.40005)
			(size 0.3683 0.3683)
			(layers "F.Cu" "F.Mask" "F.Paste")
			(net "M_BMC_DDR4_DQ<4>")
		)
		(pad "H3" smd circle
			(at -1.599946 -0.40005)
			(size 0.3683 0.3683)
			(layers "F.Cu" "F.Mask" "F.Paste")
			(net "M_BMC_DDR4_DQ<2>")
		)
		(pad "H7" smd circle
			(at 1.599946 -0.40005)
			(size 0.3683 0.3683)
			(layers "F.Cu" "F.Mask" "F.Paste")
			(net "M_BMC_DDR4_DQ<3>")
		)
		(pad "H8" smd circle
			(at 2.400046 -0.40005)
			(size 0.3683 0.3683)
			(layers "F.Cu" "F.Mask" "F.Paste")
			(net "M_BMC_DDR4_DQ<5>")
		)
		(pad "H9" smd circle
			(at 3.199892 -0.40005)
			(size 0.3683 0.3683)
			(layers "F.Cu" "F.Mask" "F.Paste")
			(net "GND")
		)
		(pad "J1" smd circle
			(at -3.199892 0.40005)
			(size 0.3683 0.3683)
			(layers "F.Cu" "F.Mask" "F.Paste")
			(net "P1V2_AUX")
		)
		(pad "J2" smd circle
			(at -2.400046 0.40005)
			(size 0.3683 0.3683)
			(layers "F.Cu" "F.Mask" "F.Paste")
			(net "P1V2_AUX")
		)
		(pad "J3" smd circle
			(at -1.599946 0.40005)
			(size 0.3683 0.3683)
			(layers "F.Cu" "F.Mask" "F.Paste")
			(net "M_BMC_DDR4_DQ<6>")
		)
		(pad "J7" smd circle
			(at 1.599946 0.40005)
			(size 0.3683 0.3683)
			(layers "F.Cu" "F.Mask" "F.Paste")
			(net "M_BMC_DDR4_DQ<7>")
		)
		(pad "J8" smd circle
			(at 2.400046 0.40005)
			(size 0.3683 0.3683)
			(layers "F.Cu" "F.Mask" "F.Paste")
			(net "P1V2_AUX")
		)
		(pad "J9" smd circle
			(at 3.199892 0.40005)
			(size 0.3683 0.3683)
			(layers "F.Cu" "F.Mask" "F.Paste")
			(net "P1V2_AUX")
		)
		(pad "K1" smd circle
			(at -3.199892 1.199896)
			(size 0.3683 0.3683)
			(layers "F.Cu" "F.Mask" "F.Paste")
			(net "GND")
		)
		(pad "K2" smd circle
			(at -2.400046 1.199896)
			(size 0.3683 0.3683)
			(layers "F.Cu" "F.Mask" "F.Paste")
			(net "M_BMC_DDR4_MCKE")
		)
		(pad "K3" smd circle
			(at -1.599946 1.199896)
			(size 0.3683 0.3683)
			(layers "F.Cu" "F.Mask" "F.Paste")
			(net "M_BMC_DDR4_MODT")
		)
		(pad "K7" smd circle
			(at 1.599946 1.199896)
			(size 0.3683 0.3683)
			(layers "F.Cu" "F.Mask" "F.Paste")
			(net "M_BMC_DDR4_MCLK_DP")
		)
		(pad "K8" smd circle
			(at 2.400046 1.199896)
			(size 0.3683 0.3683)
			(layers "F.Cu" "F.Mask" "F.Paste")
			(net "M_BMC_DDR4_MCLK_DN")
		)
		(pad "K9" smd circle
			(at 3.199892 1.199896)
			(size 0.3683 0.3683)
			(layers "F.Cu" "F.Mask" "F.Paste")
			(net "GND")
		)
		(pad "L1" smd circle
			(at -3.199892 1.999996)
			(size 0.3683 0.3683)
			(layers "F.Cu" "F.Mask" "F.Paste")
			(net "P1V2_AUX")
		)
		(pad "L2" smd circle
			(at -2.400046 1.999996)
			(size 0.3683 0.3683)
			(layers "F.Cu" "F.Mask" "F.Paste")
			(net "M_BMC_DDR4_MWE_N")
		)
		(pad "L3" smd circle
			(at -1.599946 1.999996)
			(size 0.3683 0.3683)
			(layers "F.Cu" "F.Mask" "F.Paste")
			(net "M_BMC_DDR4_MACT_N")
		)
		(pad "L7" smd circle
			(at 1.599946 1.999996)
			(size 0.3683 0.3683)
			(layers "F.Cu" "F.Mask" "F.Paste")
			(net "M_BMC_DDR4_MCS_N")
		)
		(pad "L8" smd circle
			(at 2.400046 1.999996)
			(size 0.3683 0.3683)
			(layers "F.Cu" "F.Mask" "F.Paste")
			(net "M_BMC_DDR4_MRAS_N")
		)
		(pad "L9" smd circle
			(at 3.199892 1.999996)
			(size 0.3683 0.3683)
			(layers "F.Cu" "F.Mask" "F.Paste")
			(net "P1V2_AUX")
		)
		(pad "M1" smd circle
			(at -3.199892 2.800096)
			(size 0.3683 0.3683)
			(layers "F.Cu" "F.Mask" "F.Paste")
			(net "P0V6_DDR_VREF_AUX")
		)
		(pad "M2" smd circle
			(at -2.400046 2.800096)
			(size 0.3683 0.3683)
			(layers "F.Cu" "F.Mask" "F.Paste")
			(net "M_BMC_DDR4_MBG0")
		)
		(pad "M3" smd circle
			(at -1.599946 2.800096)
			(size 0.3683 0.3683)
			(layers "F.Cu" "F.Mask" "F.Paste")
			(net "M_BMC_DDR4_MA<10>")
		)
		(pad "M7" smd circle
			(at 1.599946 2.800096)
			(size 0.3683 0.3683)
			(layers "F.Cu" "F.Mask" "F.Paste")
			(net "M_BMC_DDR4_MA<12>")
		)
		(pad "M8" smd circle
			(at 2.400046 2.800096)
			(size 0.3683 0.3683)
			(layers "F.Cu" "F.Mask" "F.Paste")
			(net "M_BMC_DDR4_MCAS_N")
		)
		(pad "M9" smd circle
			(at 3.199892 2.800096)
			(size 0.3683 0.3683)
			(layers "F.Cu" "F.Mask" "F.Paste")
			(net "M_BMC_DDR4_BG1")
		)
		(pad "N1" smd circle
			(at -3.199892 3.599942)
			(size 0.3683 0.3683)
			(layers "F.Cu" "F.Mask" "F.Paste")
			(net "GND")
		)
		(pad "N2" smd circle
			(at -2.400046 3.599942)
			(size 0.3683 0.3683)
			(layers "F.Cu" "F.Mask" "F.Paste")
			(net "M_BMC_DDR4_MBA0")
		)
		(pad "N3" smd circle
			(at -1.599946 3.599942)
			(size 0.3683 0.3683)
			(layers "F.Cu" "F.Mask" "F.Paste")
			(net "M_BMC_DDR4_MA<4>")
		)
		(pad "N7" smd circle
			(at 1.599946 3.599942)
			(size 0.3683 0.3683)
			(layers "F.Cu" "F.Mask" "F.Paste")
			(net "M_BMC_DDR4_MA<3>")
		)
		(pad "N8" smd circle
			(at 2.400046 3.599942)
			(size 0.3683 0.3683)
			(layers "F.Cu" "F.Mask" "F.Paste")
			(net "M_BMC_DDR4_MBA1")
		)
		(pad "N9" smd circle
			(at 3.199892 3.599942)
			(size 0.3683 0.3683)
			(layers "F.Cu" "F.Mask" "F.Paste")
			(net "PD_M_BMC_DDR4_TEN")
		)
		(pad "P1" smd circle
			(at -3.199892 4.400042)
			(size 0.3683 0.3683)
			(layers "F.Cu" "F.Mask" "F.Paste")
			(net "M_BMC_DDR4_RST_N")
		)
		(pad "P2" smd circle
			(at -2.400046 4.400042)
			(size 0.3683 0.3683)
			(layers "F.Cu" "F.Mask" "F.Paste")
			(net "M_BMC_DDR4_MA<6>")
		)
		(pad "P3" smd circle
			(at -1.599946 4.400042)
			(size 0.3683 0.3683)
			(layers "F.Cu" "F.Mask" "F.Paste")
			(net "M_BMC_DDR4_MA<0>")
		)
		(pad "P7" smd circle
			(at 1.599946 4.400042)
			(size 0.3683 0.3683)
			(layers "F.Cu" "F.Mask" "F.Paste")
			(net "M_BMC_DDR4_MA<1>")
		)
		(pad "P8" smd circle
			(at 2.400046 4.400042)
			(size 0.3683 0.3683)
			(layers "F.Cu" "F.Mask" "F.Paste")
			(net "M_BMC_DDR4_MA<5>")
		)
		(pad "P9" smd circle
			(at 3.199892 4.400042)
			(size 0.3683 0.3683)
			(layers "F.Cu" "F.Mask" "F.Paste")
			(net "M_BMC_DDR4_ALERT_N")
		)
		(pad "R1" smd circle
			(at -3.199892 5.199888)
			(size 0.3683 0.3683)
			(layers "F.Cu" "F.Mask" "F.Paste")
			(net "P1V2_AUX")
		)
		(pad "R2" smd circle
			(at -2.400046 5.199888)
			(size 0.3683 0.3683)
			(layers "F.Cu" "F.Mask" "F.Paste")
			(net "M_BMC_DDR4_MA<8>")
		)
		(pad "R3" smd circle
			(at -1.599946 5.199888)
			(size 0.3683 0.3683)
			(layers "F.Cu" "F.Mask" "F.Paste")
			(net "M_BMC_DDR4_MA<2>")
		)
		(pad "R7" smd circle
			(at 1.599946 5.199888)
			(size 0.3683 0.3683)
			(layers "F.Cu" "F.Mask" "F.Paste")
			(net "M_BMC_DDR4_MA<9>")
		)
		(pad "R8" smd circle
			(at 2.400046 5.199888)
			(size 0.3683 0.3683)
			(layers "F.Cu" "F.Mask" "F.Paste")
			(net "M_BMC_DDR4_MA<7>")
		)
		(pad "R9" smd circle
			(at 3.199892 5.199888)
			(size 0.3683 0.3683)
			(layers "F.Cu" "F.Mask" "F.Paste")
			(net "P2V5_AUX")
		)
		(pad "T1" smd circle
			(at -3.199892 5.999988)
			(size 0.3683 0.3683)
			(layers "F.Cu" "F.Mask" "F.Paste")
			(net "GND")
		)
		(pad "T2" smd circle
			(at -2.400046 5.999988)
			(size 0.3683 0.3683)
			(layers "F.Cu" "F.Mask" "F.Paste")
			(net "M_BMC_DDR4_MA<11>")
		)
		(pad "T3" smd circle
			(at -1.599946 5.999988)
			(size 0.3683 0.3683)
			(layers "F.Cu" "F.Mask" "F.Paste")
			(net "PD_M_BMC_DDR4_PAR")
		)
		(pad "T7" smd circle
			(at 1.599946 5.999988)
			(size 0.3683 0.3683)
			(layers "F.Cu" "F.Mask" "F.Paste")
			(net "GND")
		)
		(pad "T8" smd circle
			(at 2.400046 5.999988)
			(size 0.3683 0.3683)
			(layers "F.Cu" "F.Mask" "F.Paste")
			(net "M_BMC_DDR4_MA<13>")
		)
		(pad "T9" smd circle
			(at 3.199892 5.999988)
			(size 0.3683 0.3683)
			(layers "F.Cu" "F.Mask" "F.Paste")
			(net "P1V2_AUX")
		)
	)
)
